(kicad_pcb
	(version 20260206)
	(generator "pcbnew")
	(generator_version "10.0")
	(general
		(thickness 1.6)
		(legacy_teardrops no)
	)
	(paper "A4")
	(title_block
		(title "01162023_DA0F0TEBIF0_F0T_Expander_BD_F_brd_V02_OCP.brd")
		(comment 1 "Grand Teton / footprints 3967-3972 of 9728")
	)
	(layers
		(0 "F.Cu" signal "TOP")
		(4 "In1.Cu" signal "GND")
		(6 "In2.Cu" signal "VCC")
		(8 "In3.Cu" signal "VCC1")
		(10 "In4.Cu" signal "GND1")
		(12 "In5.Cu" signal "IN1")
		(14 "In6.Cu" signal "GND2")
		(16 "In7.Cu" signal "IN2")
		(18 "In8.Cu" signal "GND3")
		(20 "In9.Cu" signal "IN3")
		(22 "In10.Cu" signal "GND4")
		(24 "In11.Cu" signal "IN4")
		(26 "In12.Cu" signal "GND5")
		(28 "In13.Cu" signal "IN5")
		(30 "In14.Cu" signal "GND6")
		(32 "In15.Cu" signal "IN6")
		(34 "In16.Cu" signal "GND7")
		(2 "B.Cu" signal "BOTTOM")
		(9 "F.Adhes" user "F.Adhesive")
		(11 "B.Adhes" user "B.Adhesive")
		(13 "F.Paste" user "Package Geometry/Pastemask Top")
		(15 "B.Paste" user "Package Geometry/Pastemask Bottom")
		(5 "F.SilkS" user "Ref Des/Silkscreen Top")
		(7 "B.SilkS" user "Ref Des/Silkscreen Bottom")
		(1 "F.Mask" user "Board Geometry/Soldermask Top")
		(3 "B.Mask" user "Board Geometry/Soldermask Bottom")
		(17 "Dwgs.User" user "User.Drawings")
		(19 "Cmts.User" user "User.Comments")
		(21 "Eco1.User" user "User.Eco1")
		(23 "Eco2.User" user "User.Eco2")
		(25 "Edge.Cuts" user "Board Geometry/Outline")
		(27 "Margin" user)
		(31 "F.CrtYd" user "Package Geometry/Place Bound Top")
		(29 "B.CrtYd" user "Package Geometry/Place Bound Bottom")
		(35 "F.Fab" user "Ref Des/Assembly Top")
		(33 "B.Fab" user "Ref Des/Assembly Bottom")
	)
	(footprint ""
		(layer "F.Cu")
		(at 153.285444 -115.2652 90)
		(property "Reference" "R146"
			(at 0 0 90)
			(layer "F.SilkS")
			(hide yes)
			(effects
				(font
					(size 1.27 1.27)
				)
			)
		)
		(property "Value" ""
			(at 0 0 90)
			(layer "F.Fab")
			(effects
				(font
					(size 1.27 1.27)
				)
			)
		)
		(duplicate_pad_numbers_are_jumpers no)
		(fp_line
			(start 0.7874 -0.4064)
			(end 0.7874 0.4064)
			(stroke
				(width 0.1524)
				(type default)
			)
			(layer "F.SilkS")
		)
		(fp_line
			(start -0.7874 -0.4064)
			(end 0.7874 -0.4064)
			(stroke
				(width 0.1524)
				(type default)
			)
			(layer "F.SilkS")
		)
		(fp_line
			(start 0.7874 0.4064)
			(end -0.7874 0.4064)
			(stroke
				(width 0.1524)
				(type default)
			)
			(layer "F.SilkS")
		)
		(fp_line
			(start -0.7874 0.4064)
			(end -0.7874 -0.4064)
			(stroke
				(width 0.1524)
				(type default)
			)
			(layer "F.SilkS")
		)
		(fp_line
			(start -0.12065 -0.305054)
			(end -0.12065 -0.2794)
			(stroke
				(width 0.1)
				(type default)
			)
			(layer "F.Fab")
		)
		(fp_line
			(start -0.67945 -0.305054)
			(end -0.12065 -0.305054)
			(stroke
				(width 0.1)
				(type default)
			)
			(layer "F.Fab")
		)
		(fp_line
			(start 0.67945 -0.3048)
			(end 0.67945 0.3048)
			(stroke
				(width 0.1)
				(type default)
			)
			(layer "F.Fab")
		)
		(fp_line
			(start 0.12065 -0.3048)
			(end 0.67945 -0.3048)
			(stroke
				(width 0.1)
				(type default)
			)
			(layer "F.Fab")
		)
		(fp_line
			(start 0.12065 -0.2794)
			(end 0.12065 -0.3048)
			(stroke
				(width 0.1)
				(type default)
			)
			(layer "F.Fab")
		)
		(fp_line
			(start -0.12065 -0.2794)
			(end 0.12065 -0.2794)
			(stroke
				(width 0.1)
				(type default)
			)
			(layer "F.Fab")
		)
		(fp_line
			(start 0.120396 0.2794)
			(end -0.12065 0.2794)
			(stroke
				(width 0.1)
				(type default)
			)
			(layer "F.Fab")
		)
		(fp_line
			(start -0.12065 0.2794)
			(end -0.12065 0.3048)
			(stroke
				(width 0.1)
				(type default)
			)
			(layer "F.Fab")
		)
		(fp_line
			(start 0.67945 0.3048)
			(end 0.120396 0.3048)
			(stroke
				(width 0.1)
				(type default)
			)
			(layer "F.Fab")
		)
		(fp_line
			(start 0.120396 0.3048)
			(end 0.120396 0.2794)
			(stroke
				(width 0.1)
				(type default)
			)
			(layer "F.Fab")
		)
		(fp_line
			(start -0.12065 0.3048)
			(end -0.67945 0.3048)
			(stroke
				(width 0.1)
				(type default)
			)
			(layer "F.Fab")
		)
		(fp_line
			(start -0.67945 0.3048)
			(end -0.67945 -0.305054)
			(stroke
				(width 0.1)
				(type default)
			)
			(layer "F.Fab")
		)
		(pad "1" smd circle
			(at -0.40005 0 90)
			(size 0 0)
			(layers "F.Cu" "F.Mask" "F.Paste")
			(net "P3V3_AUX")
		)
		(pad "2" smd circle
			(at 0.40005 0 90)
			(size 0 0)
			(layers "F.Cu" "F.Mask" "F.Paste")
			(net "HP_NIC2_EN")
		)
	)
	(footprint ""
		(layer "F.Cu")
		(at 224.38868 -276.19325)
		(property "Reference" "R789"
			(at 0 0 0)
			(layer "F.SilkS")
			(hide yes)
			(effects
				(font
					(size 1.27 1.27)
				)
			)
		)
		(property "Value" ""
			(at 0 0 0)
			(layer "F.Fab")
			(effects
				(font
					(size 1.27 1.27)
				)
			)
		)
		(duplicate_pad_numbers_are_jumpers no)
		(fp_line
			(start -0.7874 -0.4064)
			(end 0.7874 -0.4064)
			(stroke
				(width 0.1524)
				(type default)
			)
			(layer "F.SilkS")
		)
		(fp_line
			(start -0.7874 0.4064)
			(end -0.7874 -0.4064)
			(stroke
				(width 0.1524)
				(type default)
			)
			(layer "F.SilkS")
		)
		(fp_line
			(start 0.7874 -0.4064)
			(end 0.7874 0.4064)
			(stroke
				(width 0.1524)
				(type default)
			)
			(layer "F.SilkS")
		)
		(fp_line
			(start 0.7874 0.4064)
			(end -0.7874 0.4064)
			(stroke
				(width 0.1524)
				(type default)
			)
			(layer "F.SilkS")
		)
		(fp_line
			(start -0.67945 -0.305054)
			(end -0.12065 -0.305054)
			(stroke
				(width 0.1)
				(type default)
			)
			(layer "F.Fab")
		)
		(fp_line
			(start -0.67945 0.3048)
			(end -0.67945 -0.305054)
			(stroke
				(width 0.1)
				(type default)
			)
			(layer "F.Fab")
		)
		(fp_line
			(start -0.12065 -0.305054)
			(end -0.12065 -0.2794)
			(stroke
				(width 0.1)
				(type default)
			)
			(layer "F.Fab")
		)
		(fp_line
			(start -0.12065 -0.2794)
			(end 0.12065 -0.2794)
			(stroke
				(width 0.1)
				(type default)
			)
			(layer "F.Fab")
		)
		(fp_line
			(start -0.12065 0.2794)
			(end -0.12065 0.3048)
			(stroke
				(width 0.1)
				(type default)
			)
			(layer "F.Fab")
		)
		(fp_line
			(start -0.12065 0.3048)
			(end -0.67945 0.3048)
			(stroke
				(width 0.1)
				(type default)
			)
			(layer "F.Fab")
		)
		(fp_line
			(start 0.120396 0.2794)
			(end -0.12065 0.2794)
			(stroke
				(width 0.1)
				(type default)
			)
			(layer "F.Fab")
		)
		(fp_line
			(start 0.120396 0.3048)
			(end 0.120396 0.2794)
			(stroke
				(width 0.1)
				(type default)
			)
			(layer "F.Fab")
		)
		(fp_line
			(start 0.12065 -0.3048)
			(end 0.67945 -0.3048)
			(stroke
				(width 0.1)
				(type default)
			)
			(layer "F.Fab")
		)
		(fp_line
			(start 0.12065 -0.2794)
			(end 0.12065 -0.3048)
			(stroke
				(width 0.1)
				(type default)
			)
			(layer "F.Fab")
		)
		(fp_line
			(start 0.67945 -0.3048)
			(end 0.67945 0.3048)
			(stroke
				(width 0.1)
				(type default)
			)
			(layer "F.Fab")
		)
		(fp_line
			(start 0.67945 0.3048)
			(end 0.120396 0.3048)
			(stroke
				(width 0.1)
				(type default)
			)
			(layer "F.Fab")
		)
		(pad "1" smd circle
			(at -0.40005 0)
			(size 0 0)
			(layers "F.Cu" "F.Mask" "F.Paste")
			(net "P1V25_PEX1")
		)
		(pad "2" smd circle
			(at 0.40005 0)
			(size 0 0)
			(layers "F.Cu" "F.Mask" "F.Paste")
			(net "P12V_PEX1_P1V25_VIN_N")
		)
	)
	(footprint ""
		(layer "F.Cu")
		(at 264.909046 -27.04973 180)
		(property "Reference" "C2772"
			(at 0 0 180)
			(layer "F.SilkS")
			(hide yes)
			(effects
				(font
					(size 1.27 1.27)
				)
			)
		)
		(property "Value" ""
			(at 0 0 180)
			(layer "F.Fab")
			(effects
				(font
					(size 1.27 1.27)
				)
			)
		)
		(duplicate_pad_numbers_are_jumpers no)
		(fp_line
			(start 0.7874 0.4064)
			(end -0.7874 0.4064)
			(stroke
				(width 0.1524)
				(type default)
			)
			(layer "F.SilkS")
		)
		(fp_line
			(start 0.7874 -0.4064)
			(end 0.7874 0.4064)
			(stroke
				(width 0.1524)
				(type default)
			)
			(layer "F.SilkS")
		)
		(fp_line
			(start -0.7874 0.4064)
			(end -0.7874 -0.4064)
			(stroke
				(width 0.1524)
				(type default)
			)
			(layer "F.SilkS")
		)
		(fp_line
			(start -0.7874 -0.4064)
			(end 0.7874 -0.4064)
			(stroke
				(width 0.1524)
				(type default)
			)
			(layer "F.SilkS")
		)
		(fp_line
			(start 0.67945 0.3048)
			(end 0.120396 0.3048)
			(stroke
				(width 0.1)
				(type default)
			)
			(layer "F.Fab")
		)
		(fp_line
			(start 0.67945 -0.3048)
			(end 0.67945 0.3048)
			(stroke
				(width 0.1)
				(type default)
			)
			(layer "F.Fab")
		)
		(fp_line
			(start 0.12065 -0.2794)
			(end 0.12065 -0.3048)
			(stroke
				(width 0.1)
				(type default)
			)
			(layer "F.Fab")
		)
		(fp_line
			(start 0.12065 -0.3048)
			(end 0.67945 -0.3048)
			(stroke
				(width 0.1)
				(type default)
			)
			(layer "F.Fab")
		)
		(fp_line
			(start 0.120396 0.3048)
			(end 0.120396 0.2794)
			(stroke
				(width 0.1)
				(type default)
			)
			(layer "F.Fab")
		)
		(fp_line
			(start 0.120396 0.2794)
			(end -0.12065 0.2794)
			(stroke
				(width 0.1)
				(type default)
			)
			(layer "F.Fab")
		)
		(fp_line
			(start -0.12065 0.3048)
			(end -0.67945 0.3048)
			(stroke
				(width 0.1)
				(type default)
			)
			(layer "F.Fab")
		)
		(fp_line
			(start -0.12065 0.2794)
			(end -0.12065 0.3048)
			(stroke
				(width 0.1)
				(type default)
			)
			(layer "F.Fab")
		)
		(fp_line
			(start -0.12065 -0.2794)
			(end 0.12065 -0.2794)
			(stroke
				(width 0.1)
				(type default)
			)
			(layer "F.Fab")
		)
		(fp_line
			(start -0.12065 -0.305054)
			(end -0.12065 -0.2794)
			(stroke
				(width 0.1)
				(type default)
			)
			(layer "F.Fab")
		)
		(fp_line
			(start -0.67945 0.3048)
			(end -0.67945 -0.305054)
			(stroke
				(width 0.1)
				(type default)
			)
			(layer "F.Fab")
		)
		(fp_line
			(start -0.67945 -0.305054)
			(end -0.12065 -0.305054)
			(stroke
				(width 0.1)
				(type default)
			)
			(layer "F.Fab")
		)
		(pad "1" smd circle
			(at -0.40005 0 180)
			(size 0 0)
			(layers "F.Cu" "F.Mask" "F.Paste")
			(net "PRSNT_SSD9_R_N")
		)
		(pad "2" smd circle
			(at 0.40005 0 180)
			(size 0 0)
			(layers "F.Cu" "F.Mask" "F.Paste")
			(net "GND")
		)
	)
	(footprint ""
		(layer "F.Cu")
		(at 58.709052 -27.04973 180)
		(property "Reference" "C2765"
			(at 0 0 180)
			(layer "F.SilkS")
			(hide yes)
			(effects
				(font
					(size 1.27 1.27)
				)
			)
		)
		(property "Value" ""
			(at 0 0 180)
			(layer "F.Fab")
			(effects
				(font
					(size 1.27 1.27)
				)
			)
		)
		(duplicate_pad_numbers_are_jumpers no)
		(fp_line
			(start 0.7874 0.4064)
			(end -0.7874 0.4064)
			(stroke
				(width 0.1524)
				(type default)
			)
			(layer "F.SilkS")
		)
		(fp_line
			(start 0.7874 -0.4064)
			(end 0.7874 0.4064)
			(stroke
				(width 0.1524)
				(type default)
			)
			(layer "F.SilkS")
		)
		(fp_line
			(start -0.7874 0.4064)
			(end -0.7874 -0.4064)
			(stroke
				(width 0.1524)
				(type default)
			)
			(layer "F.SilkS")
		)
		(fp_line
			(start -0.7874 -0.4064)
			(end 0.7874 -0.4064)
			(stroke
				(width 0.1524)
				(type default)
			)
			(layer "F.SilkS")
		)
		(fp_line
			(start 0.67945 0.3048)
			(end 0.120396 0.3048)
			(stroke
				(width 0.1)
				(type default)
			)
			(layer "F.Fab")
		)
		(fp_line
			(start 0.67945 -0.3048)
			(end 0.67945 0.3048)
			(stroke
				(width 0.1)
				(type default)
			)
			(layer "F.Fab")
		)
		(fp_line
			(start 0.12065 -0.2794)
			(end 0.12065 -0.3048)
			(stroke
				(width 0.1)
				(type default)
			)
			(layer "F.Fab")
		)
		(fp_line
			(start 0.12065 -0.3048)
			(end 0.67945 -0.3048)
			(stroke
				(width 0.1)
				(type default)
			)
			(layer "F.Fab")
		)
		(fp_line
			(start 0.120396 0.3048)
			(end 0.120396 0.2794)
			(stroke
				(width 0.1)
				(type default)
			)
			(layer "F.Fab")
		)
		(fp_line
			(start 0.120396 0.2794)
			(end -0.12065 0.2794)
			(stroke
				(width 0.1)
				(type default)
			)
			(layer "F.Fab")
		)
		(fp_line
			(start -0.12065 0.3048)
			(end -0.67945 0.3048)
			(stroke
				(width 0.1)
				(type default)
			)
			(layer "F.Fab")
		)
		(fp_line
			(start -0.12065 0.2794)
			(end -0.12065 0.3048)
			(stroke
				(width 0.1)
				(type default)
			)
			(layer "F.Fab")
		)
		(fp_line
			(start -0.12065 -0.2794)
			(end 0.12065 -0.2794)
			(stroke
				(width 0.1)
				(type default)
			)
			(layer "F.Fab")
		)
		(fp_line
			(start -0.12065 -0.305054)
			(end -0.12065 -0.2794)
			(stroke
				(width 0.1)
				(type default)
			)
			(layer "F.Fab")
		)
		(fp_line
			(start -0.67945 0.3048)
			(end -0.67945 -0.305054)
			(stroke
				(width 0.1)
				(type default)
			)
			(layer "F.Fab")
		)
		(fp_line
			(start -0.67945 -0.305054)
			(end -0.12065 -0.305054)
			(stroke
				(width 0.1)
				(type default)
			)
			(layer "F.Fab")
		)
		(pad "1" smd circle
			(at -0.40005 0 180)
			(size 0 0)
			(layers "F.Cu" "F.Mask" "F.Paste")
			(net "PRSNT_SSD2_R_N")
		)
		(pad "2" smd circle
			(at 0.40005 0 180)
			(size 0 0)
			(layers "F.Cu" "F.Mask" "F.Paste")
			(net "GND")
		)
	)
	(footprint ""
		(layer "F.Cu")
		(at 438.339484 -96.811592 -90)
		(property "Reference" "R763"
			(at 0 0 270)
			(layer "F.SilkS")
			(hide yes)
			(effects
				(font
					(size 1.27 1.27)
				)
			)
		)
		(property "Value" ""
			(at 0 0 270)
			(layer "F.Fab")
			(effects
				(font
					(size 1.27 1.27)
				)
			)
		)
		(duplicate_pad_numbers_are_jumpers no)
		(fp_line
			(start -0.7874 0.4064)
			(end -0.7874 -0.4064)
			(stroke
				(width 0.1524)
				(type default)
			)
			(layer "F.SilkS")
		)
		(fp_line
			(start 0.7874 0.4064)
			(end -0.7874 0.4064)
			(stroke
				(width 0.1524)
				(type default)
			)
			(layer "F.SilkS")
		)
		(fp_line
			(start -0.7874 -0.4064)
			(end 0.7874 -0.4064)
			(stroke
				(width 0.1524)
				(type default)
			)
			(layer "F.SilkS")
		)
		(fp_line
			(start 0.7874 -0.4064)
			(end 0.7874 0.4064)
			(stroke
				(width 0.1524)
				(type default)
			)
			(layer "F.SilkS")
		)
		(fp_line
			(start -0.67945 0.3048)
			(end -0.67945 -0.305054)
			(stroke
				(width 0.1)
				(type default)
			)
			(layer "F.Fab")
		)
		(fp_line
			(start -0.12065 0.3048)
			(end -0.67945 0.3048)
			(stroke
				(width 0.1)
				(type default)
			)
			(layer "F.Fab")
		)
		(fp_line
			(start 0.120396 0.3048)
			(end 0.120396 0.2794)
			(stroke
				(width 0.1)
				(type default)
			)
			(layer "F.Fab")
		)
		(fp_line
			(start 0.67945 0.3048)
			(end 0.120396 0.3048)
			(stroke
				(width 0.1)
				(type default)
			)
			(layer "F.Fab")
		)
		(fp_line
			(start -0.12065 0.2794)
			(end -0.12065 0.3048)
			(stroke
				(width 0.1)
				(type default)
			)
			(layer "F.Fab")
		)
		(fp_line
			(start 0.120396 0.2794)
			(end -0.12065 0.2794)
			(stroke
				(width 0.1)
				(type default)
			)
			(layer "F.Fab")
		)
		(fp_line
			(start -0.12065 -0.2794)
			(end 0.12065 -0.2794)
			(stroke
				(width 0.1)
				(type default)
			)
			(layer "F.Fab")
		)
		(fp_line
			(start 0.12065 -0.2794)
			(end 0.12065 -0.3048)
			(stroke
				(width 0.1)
				(type default)
			)
			(layer "F.Fab")
		)
		(fp_line
			(start 0.12065 -0.3048)
			(end 0.67945 -0.3048)
			(stroke
				(width 0.1)
				(type default)
			)
			(layer "F.Fab")
		)
		(fp_line
			(start 0.67945 -0.3048)
			(end 0.67945 0.3048)
			(stroke
				(width 0.1)
				(type default)
			)
			(layer "F.Fab")
		)
		(fp_line
			(start -0.67945 -0.305054)
			(end -0.12065 -0.305054)
			(stroke
				(width 0.1)
				(type default)
			)
			(layer "F.Fab")
		)
		(fp_line
			(start -0.12065 -0.305054)
			(end -0.12065 -0.2794)
			(stroke
				(width 0.1)
				(type default)
			)
			(layer "F.Fab")
		)
		(pad "1" smd circle
			(at -0.40005 0 270)
			(size 0 0)
			(layers "F.Cu" "F.Mask" "F.Paste")
			(net "NIC7_ADC_A0")
		)
		(pad "2" smd circle
			(at 0.40005 0 270)
			(size 0 0)
			(layers "F.Cu" "F.Mask" "F.Paste")
			(net "GND")
		)
	)
	(footprint ""
		(layer "F.Cu")
		(at 228.79304 -94.073726 180)
		(property "Reference" "R5441"
			(at 0 0 180)
			(layer "F.SilkS")
			(hide yes)
			(effects
				(font
					(size 1.27 1.27)
				)
			)
		)
		(property "Value" ""
			(at 0 0 180)
			(layer "F.Fab")
			(effects
				(font
					(size 1.27 1.27)
				)
			)
		)
		(duplicate_pad_numbers_are_jumpers no)
		(fp_line
			(start 0.7874 0.4064)
			(end -0.7874 0.4064)
			(stroke
				(width 0.1524)
				(type default)
			)
			(layer "F.SilkS")
		)
		(fp_line
			(start 0.7874 -0.4064)
			(end 0.7874 0.4064)
			(stroke
				(width 0.1524)
				(type default)
			)
			(layer "F.SilkS")
		)
		(fp_line
			(start -0.7874 0.4064)
			(end -0.7874 -0.4064)
			(stroke
				(width 0.1524)
				(type default)
			)
			(layer "F.SilkS")
		)
		(fp_line
			(start -0.7874 -0.4064)
			(end 0.7874 -0.4064)
			(stroke
				(width 0.1524)
				(type default)
			)
			(layer "F.SilkS")
		)
		(fp_line
			(start 0.67945 0.3048)
			(end 0.120396 0.3048)
			(stroke
				(width 0.1)
				(type default)
			)
			(layer "F.Fab")
		)
		(fp_line
			(start 0.67945 -0.3048)
			(end 0.67945 0.3048)
			(stroke
				(width 0.1)
				(type default)
			)
			(layer "F.Fab")
		)
		(fp_line
			(start 0.12065 -0.2794)
			(end 0.12065 -0.3048)
			(stroke
				(width 0.1)
				(type default)
			)
			(layer "F.Fab")
		)
		(fp_line
			(start 0.12065 -0.3048)
			(end 0.67945 -0.3048)
			(stroke
				(width 0.1)
				(type default)
			)
			(layer "F.Fab")
		)
		(fp_line
			(start 0.120396 0.3048)
			(end 0.120396 0.2794)
			(stroke
				(width 0.1)
				(type default)
			)
			(layer "F.Fab")
		)
		(fp_line
			(start 0.120396 0.2794)
			(end -0.12065 0.2794)
			(stroke
				(width 0.1)
				(type default)
			)
			(layer "F.Fab")
		)
		(fp_line
			(start -0.12065 0.3048)
			(end -0.67945 0.3048)
			(stroke
				(width 0.1)
				(type default)
			)
			(layer "F.Fab")
		)
		(fp_line
			(start -0.12065 0.2794)
			(end -0.12065 0.3048)
			(stroke
				(width 0.1)
				(type default)
			)
			(layer "F.Fab")
		)
		(fp_line
			(start -0.12065 -0.2794)
			(end 0.12065 -0.2794)
			(stroke
				(width 0.1)
				(type default)
			)
			(layer "F.Fab")
		)
		(fp_line
			(start -0.12065 -0.305054)
			(end -0.12065 -0.2794)
			(stroke
				(width 0.1)
				(type default)
			)
			(layer "F.Fab")
		)
		(fp_line
			(start -0.67945 0.3048)
			(end -0.67945 -0.305054)
			(stroke
				(width 0.1)
				(type default)
			)
			(layer "F.Fab")
		)
		(fp_line
			(start -0.67945 -0.305054)
			(end -0.12065 -0.305054)
			(stroke
				(width 0.1)
				(type default)
			)
			(layer "F.Fab")
		)
		(pad "1" smd circle
			(at -0.40005 0 180)
			(size 0 0)
			(layers "F.Cu" "F.Mask" "F.Paste")
			(net "PEX_USB_HUB_PSELF")
		)
		(pad "2" smd circle
			(at 0.40005 0 180)
			(size 0 0)
			(layers "F.Cu" "F.Mask" "F.Paste")
			(net "GND")
		)
	)
)
